(kicad_pcb
	(version 20241229)
	(generator "pcbnew")
	(generator_version "9.0")
	(general
		(thickness 1.61)
		(legacy_teardrops no)
	)
	(paper "A3")
	(title_block
		(title "RDIMM DDR5 Tester")
		(date "2026-05-21")
		(rev "2.2.0")
		(company "Antmicro")
		(comment 9 "footprints 780-784 of 796")
	)
	(layers
		(0 "F.Cu" signal)
		(4 "In1.Cu" power)
		(6 "In2.Cu" mixed)
		(8 "In3.Cu" power)
		(10 "In4.Cu" mixed)
		(12 "In5.Cu" power)
		(14 "In6.Cu" mixed)
		(16 "In7.Cu" power)
		(18 "In8.Cu" power)
		(20 "In9.Cu" mixed)
		(22 "In10.Cu" power)
		(2 "B.Cu" signal)
		(9 "F.Adhes" user "F.Adhesive")
		(11 "B.Adhes" user "B.Adhesive")
		(13 "F.Paste" user)
		(15 "B.Paste" user)
		(5 "F.SilkS" user "F.Silkscreen")
		(7 "B.SilkS" user "B.Silkscreen")
		(1 "F.Mask" user)
		(3 "B.Mask" user)
		(17 "Dwgs.User" user "User.Drawings")
		(19 "Cmts.User" user "User.Comments")
		(21 "Eco1.User" user "User.Eco1")
		(23 "Eco2.User" user "User.Eco2")
		(25 "Edge.Cuts" user)
		(27 "Margin" user)
		(31 "F.CrtYd" user "F.Courtyard")
		(29 "B.CrtYd" user "B.Courtyard")
		(35 "F.Fab" user)
		(33 "B.Fab" user)
	)
	(footprint "antmicro-footprints:C_0603_1608Metric"
		(layer "B.Cu")
		(at 202.4 149.5 90)
		(descr "Capacitor SMD 0603")
		(tags "capacitor 0603")
		(property "Reference" "C94"
			(at -0.9 1.8 90)
			(layer "B.SilkS")
			(effects
				(font
					(size 0.7 0.7)
					(thickness 0.15)
				)
				(justify right bottom mirror)
			)
		)
		(property "Value" "C_47u_0603"
			(at -1.42757 -1.770288 90)
			(layer "B.Fab")
			(effects
				(font
					(size 0.7 0.7)
					(thickness 0.15)
				)
				(justify right bottom mirror)
			)
		)
		(property "Datasheet" "https://www.murata.com/products/productdetail?partno=GRM188R60J476ME15%23"
			(at 0 0 90)
			(layer "F.Fab")
			(hide yes)
			(effects
				(font
					(size 1.27 1.27)
					(thickness 0.15)
				)
			)
		)
		(property "Manufacturer" "Murata"
			(at 0 0 90)
			(unlocked yes)
			(layer "B.Fab")
			(hide yes)
			(effects
				(font
					(size 1 1)
					(thickness 0.15)
				)
				(justify mirror)
			)
		)
		(property "MPN" "GRM188R60J476ME15D"
			(at 0 0 90)
			(unlocked yes)
			(layer "B.Fab")
			(hide yes)
			(effects
				(font
					(size 1 1)
					(thickness 0.15)
				)
				(justify mirror)
			)
		)
		(property "Val" "47u"
			(at 0 0 90)
			(unlocked yes)
			(layer "B.Fab")
			(hide yes)
			(effects
				(font
					(size 1 1)
					(thickness 0.15)
				)
				(justify mirror)
			)
		)
		(property "License" "Apache-2.0"
			(at 0 0 90)
			(unlocked yes)
			(layer "B.Fab")
			(hide yes)
			(effects
				(font
					(size 1 1)
					(thickness 0.15)
				)
				(justify mirror)
			)
		)
		(property "Author" "Antmicro"
			(at 0 0 90)
			(unlocked yes)
			(layer "B.Fab")
			(hide yes)
			(effects
				(font
					(size 1 1)
					(thickness 0.15)
				)
				(justify mirror)
			)
		)
		(property "Voltage" ""
			(at 0 0 90)
			(unlocked yes)
			(layer "B.Fab")
			(hide yes)
			(effects
				(font
					(size 1 1)
					(thickness 0.15)
				)
				(justify mirror)
			)
		)
		(property "Dielectric" ""
			(at 0 0 90)
			(unlocked yes)
			(layer "B.Fab")
			(hide yes)
			(effects
				(font
					(size 1 1)
					(thickness 0.15)
				)
				(justify mirror)
			)
		)
		(sheetname "/FPGA power/")
		(sheetfile "fpga-power.kicad_sch")
		(attr smd)
		(fp_line
			(start -0.15 -0.4)
			(end 0.15 -0.4)
			(stroke
				(width 0.15)
				(type solid)
			)
			(layer "B.SilkS")
		)
		(fp_line
			(start -0.15 0.4)
			(end 0.15 0.4)
			(stroke
				(width 0.15)
				(type solid)
			)
			(layer "B.SilkS")
		)
		(fp_rect
			(start -1.25 0.65)
			(end 1.25 -0.65)
			(stroke
				(width 0.05)
				(type solid)
			)
			(fill no)
			(layer "B.CrtYd")
		)
		(fp_rect
			(start -0.8 0.4)
			(end 0.8 -0.4)
			(stroke
				(width 0.15)
				(type solid)
			)
			(fill no)
			(layer "B.Fab")
		)
		(fp_text user "License: Apache-2.0"
			(at -1.682 -5.895 270)
			(layer "B.Fab")
			(effects
				(font
					(size 0.7 0.7)
					(thickness 0.15)
				)
				(justify left bottom mirror)
			)
		)
		(fp_text user "Author: Antmicro"
			(at -1.682 -4.894 270)
			(layer "B.Fab")
			(effects
				(font
					(size 0.7 0.7)
					(thickness 0.15)
				)
				(justify left bottom mirror)
			)
		)
		(fp_text user "${REFERENCE}"
			(at -1.682 -3.895 270)
			(layer "B.Fab")
			(effects
				(font
					(size 0.7 0.7)
					(thickness 0.15)
				)
				(justify left bottom mirror)
			)
		)
		(pad "1" smd roundrect
			(at -0.7 0 90)
			(size 0.8 1)
			(layers "B.Cu" "B.Mask" "B.Paste")
			(roundrect_rratio 0.2)
			(net 151 "+3V3")
			(pintype "passive")
		)
		(pad "2" smd roundrect
			(at 0.7 0 90)
			(size 0.8 1)
			(layers "B.Cu" "B.Mask" "B.Paste")
			(roundrect_rratio 0.2)
			(net 1 "GND")
			(pintype "passive")
		)
	)
	(footprint "antmicro-footprints:C_0402_1005Metric_EIA"
		(layer "B.Cu")
		(at 179 142.5 90)
		(descr "Capacitor SMD 0402 (1005 Metric), square (rectangular) end terminal, IPC_7351 nominal, (Body size source: IPC-SM-782 page 76, https://www.pcb-3d.com/wordpress/wp-content/uploads/ipc-sm-782a_amendment_1_and_2.pdf)")
		(tags "capacitor 0402")
		(property "Reference" "C71"
			(at -1.15 1.4 90)
			(layer "B.SilkS")
			(effects
				(font
					(size 0.7 0.7)
					(thickness 0.15)
				)
				(justify right bottom mirror)
			)
		)
		(property "Value" "C_10u_10V_0402"
			(at 0 -1.169 90)
			(layer "B.Fab")
			(effects
				(font
					(size 0.7 0.7)
					(thickness 0.15)
				)
				(justify right bottom mirror)
			)
		)
		(property "Datasheet" "https://www.murata.com/products/productdetail?partno=GRM155R61A106ME11%23"
			(at 0 0 90)
			(layer "F.Fab")
			(hide yes)
			(effects
				(font
					(size 1.27 1.27)
					(thickness 0.15)
				)
			)
		)
		(property "MPN" "GRM155R61A106ME11D"
			(at 0 0 90)
			(unlocked yes)
			(layer "B.Fab")
			(hide yes)
			(effects
				(font
					(size 1 1)
					(thickness 0.15)
				)
				(justify mirror)
			)
		)
		(property "Manufacturer" "Murata"
			(at 0 0 90)
			(unlocked yes)
			(layer "B.Fab")
			(hide yes)
			(effects
				(font
					(size 1 1)
					(thickness 0.15)
				)
				(justify mirror)
			)
		)
		(property "License" "Apache-2.0"
			(at 0 0 90)
			(unlocked yes)
			(layer "B.Fab")
			(hide yes)
			(effects
				(font
					(size 1 1)
					(thickness 0.15)
				)
				(justify mirror)
			)
		)
		(property "Author" "Antmicro"
			(at 0 0 90)
			(unlocked yes)
			(layer "B.Fab")
			(hide yes)
			(effects
				(font
					(size 1 1)
					(thickness 0.15)
				)
				(justify mirror)
			)
		)
		(property "Val" "10u"
			(at 0 0 90)
			(unlocked yes)
			(layer "B.Fab")
			(hide yes)
			(effects
				(font
					(size 1 1)
					(thickness 0.15)
				)
				(justify mirror)
			)
		)
		(property "Voltage" "10V"
			(at 0 0 90)
			(unlocked yes)
			(layer "B.Fab")
			(hide yes)
			(effects
				(font
					(size 1 1)
					(thickness 0.15)
				)
				(justify mirror)
			)
		)
		(property "Dielectric" "X5R"
			(at 0 0 90)
			(unlocked yes)
			(layer "B.Fab")
			(hide yes)
			(effects
				(font
					(size 1 1)
					(thickness 0.15)
				)
				(justify mirror)
			)
		)
		(sheetname "/FPGA power/")
		(sheetfile "fpga-power.kicad_sch")
		(attr smd)
		(fp_rect
			(start -0.95 0.45)
			(end 0.95 -0.45)
			(stroke
				(width 0.05)
				(type default)
			)
			(fill no)
			(layer "B.CrtYd")
		)
		(fp_line
			(start 0.498 -0.248)
			(end -0.5 -0.248)
			(stroke
				(width 0.15)
				(type solid)
			)
			(layer "B.Fab")
		)
		(fp_line
			(start -0.5 -0.248)
			(end -0.5 0.25)
			(stroke
				(width 0.15)
				(type solid)
			)
			(layer "B.Fab")
		)
		(fp_line
			(start 0.498 0.25)
			(end 0.498 -0.248)
			(stroke
				(width 0.15)
				(type solid)
			)
			(layer "B.Fab")
		)
		(fp_line
			(start -0.5 0.25)
			(end 0.498 0.25)
			(stroke
				(width 0.15)
				(type solid)
			)
			(layer "B.Fab")
		)
		(fp_text user "License: Apache-2.0"
			(at -0.9656 -4.369 270)
			(layer "B.Fab")
			(effects
				(font
					(size 0.7 0.7)
					(thickness 0.15)
				)
				(justify left bottom mirror)
			)
		)
		(fp_text user "${REFERENCE}"
			(at -0.9656 -3.169 270)
			(layer "B.Fab")
			(effects
				(font
					(size 0.7 0.7)
					(thickness 0.15)
				)
				(justify left bottom mirror)
			)
		)
		(fp_text user "Author: Antmicro"
			(at -0.9656 -5.569 270)
			(layer "B.Fab")
			(effects
				(font
					(size 0.7 0.7)
					(thickness 0.15)
				)
				(justify left bottom mirror)
			)
		)
		(pad "1" smd roundrect
			(at -0.5 0)
			(size 0.6 0.6)
			(layers "B.Cu" "B.Mask" "B.Paste")
			(roundrect_rratio 0.25)
			(net 1 "GND")
			(pintype "passive")
		)
		(pad "2" smd roundrect
			(at 0.498 0 90)
			(size 0.6 0.6)
			(layers "B.Cu" "B.Mask" "B.Paste")
			(roundrect_rratio 0.25)
			(net 687 "VDDQ")
			(pintype "passive")
		)
	)
	(footprint "antmicro-footprints:C_0603_1608Metric"
		(layer "B.Cu")
		(at 240.55 120.765)
		(descr "Capacitor SMD 0603")
		(tags "capacitor 0603")
		(property "Reference" "C323"
			(at -1.25 2.915 0)
			(layer "B.SilkS")
			(effects
				(font
					(size 0.7 0.7)
					(thickness 0.15)
				)
				(justify right bottom mirror)
			)
		)
		(property "Value" "C_10u_25V_0603"
			(at -1.42757 -1.770288 0)
			(layer "B.Fab")
			(effects
				(font
					(size 0.7 0.7)
					(thickness 0.15)
				)
				(justify right bottom mirror)
			)
		)
		(property "Datasheet" "https://product.tdk.com/en/search/capacitor/ceramic/mlcc/info?part_no=C1608X5R1E106M080AC"
			(at 0 0 0)
			(layer "F.Fab")
			(hide yes)
			(effects
				(font
					(size 1.27 1.27)
					(thickness 0.15)
				)
			)
		)
		(property "MPN" "C1608X5R1E106M080AC"
			(at 0 0 0)
			(unlocked yes)
			(layer "B.Fab")
			(hide yes)
			(effects
				(font
					(size 1 1)
					(thickness 0.15)
				)
				(justify mirror)
			)
		)
		(property "Manufacturer" "TDK"
			(at 0 0 0)
			(unlocked yes)
			(layer "B.Fab")
			(hide yes)
			(effects
				(font
					(size 1 1)
					(thickness 0.15)
				)
				(justify mirror)
			)
		)
		(property "License" "Apache-2.0"
			(at 0 0 0)
			(unlocked yes)
			(layer "B.Fab")
			(hide yes)
			(effects
				(font
					(size 1 1)
					(thickness 0.15)
				)
				(justify mirror)
			)
		)
		(property "Author" "Antmicro"
			(at 0 0 0)
			(unlocked yes)
			(layer "B.Fab")
			(hide yes)
			(effects
				(font
					(size 1 1)
					(thickness 0.15)
				)
				(justify mirror)
			)
		)
		(property "Val" "10u"
			(at 0 0 0)
			(unlocked yes)
			(layer "B.Fab")
			(hide yes)
			(effects
				(font
					(size 1 1)
					(thickness 0.15)
				)
				(justify mirror)
			)
		)
		(property "Voltage" "25V"
			(at 0 0 0)
			(unlocked yes)
			(layer "B.Fab")
			(hide yes)
			(effects
				(font
					(size 1 1)
					(thickness 0.15)
				)
				(justify mirror)
			)
		)
		(property "Dielectric" ""
			(at 0 0 0)
			(unlocked yes)
			(layer "B.Fab")
			(hide yes)
			(effects
				(font
					(size 1 1)
					(thickness 0.15)
				)
				(justify mirror)
			)
		)
		(sheetname "/Supply/")
		(sheetfile "supply.kicad_sch")
		(attr smd)
		(fp_line
			(start -0.15 -0.4)
			(end 0.15 -0.4)
			(stroke
				(width 0.15)
				(type solid)
			)
			(layer "B.SilkS")
		)
		(fp_line
			(start -0.15 0.4)
			(end 0.15 0.4)
			(stroke
				(width 0.15)
				(type solid)
			)
			(layer "B.SilkS")
		)
		(fp_rect
			(start -1.25 0.65)
			(end 1.25 -0.65)
			(stroke
				(width 0.05)
				(type solid)
			)
			(fill no)
			(layer "B.CrtYd")
		)
		(fp_rect
			(start -0.8 0.4)
			(end 0.8 -0.4)
			(stroke
				(width 0.15)
				(type solid)
			)
			(fill no)
			(layer "B.Fab")
		)
		(fp_text user "${REFERENCE}"
			(at -1.682 -3.895 180)
			(layer "B.Fab")
			(effects
				(font
					(size 0.7 0.7)
					(thickness 0.15)
				)
				(justify left bottom mirror)
			)
		)
		(fp_text user "Author: Antmicro"
			(at -1.682 -4.894 180)
			(layer "B.Fab")
			(effects
				(font
					(size 0.7 0.7)
					(thickness 0.15)
				)
				(justify left bottom mirror)
			)
		)
		(fp_text user "License: Apache-2.0"
			(at -1.682 -5.895 180)
			(layer "B.Fab")
			(effects
				(font
					(size 0.7 0.7)
					(thickness 0.15)
				)
				(justify left bottom mirror)
			)
		)
		(pad "1" smd roundrect
			(at -0.7 0)
			(size 0.8 1)
			(layers "B.Cu" "B.Mask" "B.Paste")
			(roundrect_rratio 0.2)
			(net 1 "GND")
			(pintype "passive")
		)
		(pad "2" smd roundrect
			(at 0.7 0)
			(size 0.8 1)
			(layers "B.Cu" "B.Mask" "B.Paste")
			(roundrect_rratio 0.2)
			(net 811 "/Supply/heater")
			(pintype "passive")
		)
	)
	(footprint "antmicro-footprints:R_0402_1005Metric"
		(layer "B.Cu")
		(at 254.199499 135.749)
		(descr "Resistor SMD 0402")
		(tags "resistor SMD 0402")
		(property "Reference" "R172"
			(at 1.250501 0.451 0)
			(layer "B.SilkS")
			(effects
				(font
					(size 0.7 0.7)
					(thickness 0.15)
				)
				(justify right bottom mirror)
			)
		)
		(property "Value" "R_47k_0402"
			(at -1.011843 -1.772047 0)
			(layer "B.Fab")
			(effects
				(font
					(size 0.7 0.7)
					(thickness 0.15)
				)
				(justify right bottom mirror)
			)
		)
		(property "Datasheet" "https://www.bourns.com/docs/product-datasheets/cr.pdf"
			(at 0 0 0)
			(layer "F.Fab")
			(hide yes)
			(effects
				(font
					(size 1.27 1.27)
					(thickness 0.15)
				)
			)
		)
		(property "Manufacturer" "Bourns"
			(at 0 0 0)
			(unlocked yes)
			(layer "B.Fab")
			(hide yes)
			(effects
				(font
					(size 1 1)
					(thickness 0.15)
				)
				(justify mirror)
			)
		)
		(property "MPN" "CR0402-FX-4702GLF"
			(at 0 0 0)
			(unlocked yes)
			(layer "B.Fab")
			(hide yes)
			(effects
				(font
					(size 1 1)
					(thickness 0.15)
				)
				(justify mirror)
			)
		)
		(property "Val" "47k"
			(at 0 0 0)
			(unlocked yes)
			(layer "B.Fab")
			(hide yes)
			(effects
				(font
					(size 1 1)
					(thickness 0.15)
				)
				(justify mirror)
			)
		)
		(property "License" "Apache-2.0"
			(at 0 0 0)
			(unlocked yes)
			(layer "B.Fab")
			(hide yes)
			(effects
				(font
					(size 1 1)
					(thickness 0.15)
				)
				(justify mirror)
			)
		)
		(property "Author" "Antmicro"
			(at 0 0 0)
			(unlocked yes)
			(layer "B.Fab")
			(hide yes)
			(effects
				(font
					(size 1 1)
					(thickness 0.15)
				)
				(justify mirror)
			)
		)
		(property "Tolerance" "1%"
			(at 0 0 0)
			(unlocked yes)
			(layer "B.Fab")
			(hide yes)
			(effects
				(font
					(size 1 1)
					(thickness 0.15)
				)
				(justify mirror)
			)
		)
		(sheetname "/Supply/")
		(sheetfile "supply.kicad_sch")
		(attr smd)
		(fp_rect
			(start -0.925 0.47)
			(end 0.925 -0.47)
			(stroke
				(width 0.05)
				(type default)
			)
			(fill no)
			(layer "B.CrtYd")
		)
		(fp_rect
			(start -0.5 0.25)
			(end 0.5 -0.25)
			(stroke
				(width 0.15)
				(type solid)
			)
			(fill no)
			(layer "B.Fab")
		)
		(fp_text user "License: Apache-2.0"
			(at -0.95 -5.169 180)
			(layer "B.Fab")
			(effects
				(font
					(size 0.7 0.7)
					(thickness 0.15)
				)
				(justify left bottom mirror)
			)
		)
		(fp_text user "Author: Antmicro"
			(at -0.95 -4.169 180)
			(layer "B.Fab")
			(effects
				(font
					(size 0.7 0.7)
					(thickness 0.15)
				)
				(justify left bottom mirror)
			)
		)
		(fp_text user "${REFERENCE}"
			(at -0.95 -3.168 180)
			(layer "B.Fab")
			(effects
				(font
					(size 0.7 0.7)
					(thickness 0.15)
				)
				(justify left bottom mirror)
			)
		)
		(pad "1" smd roundrect
			(at -0.48 0)
			(size 0.59 0.64)
			(layers "B.Cu" "B.Mask" "B.Paste")
			(roundrect_rratio 0.25)
			(net 286 "Net-(Q16-D)")
			(pintype "passive")
		)
		(pad "2" smd roundrect
			(at 0.48 0)
			(size 0.59 0.64)
			(layers "B.Cu" "B.Mask" "B.Paste")
			(roundrect_rratio 0.25)
			(net 38 "+3V3_AON")
			(pintype "passive")
		)
	)
	(footprint "antmicro-footprints:R_0402_1005Metric"
		(layer "B.Cu")
		(at 254.05 122.225)
		(descr "Resistor SMD 0402")
		(tags "resistor SMD 0402")
		(property "Reference" "R245"
			(at -1.4 1.625 0)
			(layer "B.SilkS")
			(effects
				(font
					(size 0.7 0.7)
					(thickness 0.15)
				)
				(justify right bottom mirror)
			)
		)
		(property "Value" "R_47k_0402"
			(at -1.011843 -1.772047 0)
			(layer "B.Fab")
			(effects
				(font
					(size 0.7 0.7)
					(thickness 0.15)
				)
				(justify right bottom mirror)
			)
		)
		(property "Datasheet" "https://www.bourns.com/docs/product-datasheets/cr.pdf"
			(at 0 0 0)
			(layer "F.Fab")
			(hide yes)
			(effects
				(font
					(size 1.27 1.27)
					(thickness 0.15)
				)
			)
		)
		(property "MPN" "CR0402-FX-4702GLF"
			(at 0 0 0)
			(unlocked yes)
			(layer "B.Fab")
			(hide yes)
			(effects
				(font
					(size 1 1)
					(thickness 0.15)
				)
				(justify mirror)
			)
		)
		(property "Manufacturer" "Bourns"
			(at 0 0 0)
			(unlocked yes)
			(layer "B.Fab")
			(hide yes)
			(effects
				(font
					(size 1 1)
					(thickness 0.15)
				)
				(justify mirror)
			)
		)
		(property "License" "Apache-2.0"
			(at 0 0 0)
			(unlocked yes)
			(layer "B.Fab")
			(hide yes)
			(effects
				(font
					(size 1 1)
					(thickness 0.15)
				)
				(justify mirror)
			)
		)
		(property "Author" "Antmicro"
			(at 0 0 0)
			(unlocked yes)
			(layer "B.Fab")
			(hide yes)
			(effects
				(font
					(size 1 1)
					(thickness 0.15)
				)
				(justify mirror)
			)
		)
		(property "Val" "47k"
			(at 0 0 0)
			(unlocked yes)
			(layer "B.Fab")
			(hide yes)
			(effects
				(font
					(size 1 1)
					(thickness 0.15)
				)
				(justify mirror)
			)
		)
		(property "Tolerance" "1%"
			(at 0 0 0)
			(unlocked yes)
			(layer "B.Fab")
			(hide yes)
			(effects
				(font
					(size 1 1)
					(thickness 0.15)
				)
				(justify mirror)
			)
		)
		(sheetname "/DDR5 RDIMM/")
		(sheetfile "ddr5-rdimm.kicad_sch")
		(attr smd)
		(fp_rect
			(start -0.925 0.47)
			(end 0.925 -0.47)
			(stroke
				(width 0.05)
				(type default)
			)
			(fill no)
			(layer "B.CrtYd")
		)
		(fp_rect
			(start -0.5 0.25)
			(end 0.5 -0.25)
			(stroke
				(width 0.15)
				(type solid)
			)
			(fill no)
			(layer "B.Fab")
		)
		(fp_text user "${REFERENCE}"
			(at -0.95 -3.168 180)
			(layer "B.Fab")
			(effects
				(font
					(size 0.7 0.7)
					(thickness 0.15)
				)
				(justify left bottom mirror)
			)
		)
		(fp_text user "License: Apache-2.0"
			(at -0.95 -5.169 180)
			(layer "B.Fab")
			(effects
				(font
					(size 0.7 0.7)
					(thickness 0.15)
				)
				(justify left bottom mirror)
			)
		)
		(fp_text user "Author: Antmicro"
			(at -0.95 -4.169 180)
			(layer "B.Fab")
			(effects
				(font
					(size 0.7 0.7)
					(thickness 0.15)
				)
				(justify left bottom mirror)
			)
		)
		(pad "1" smd roundrect
			(at -0.48 0)
			(size 0.59 0.64)
			(layers "B.Cu" "B.Mask" "B.Paste")
			(roundrect_rratio 0.25)
			(net 1 "GND")
			(pintype "passive")
		)
		(pad "2" smd roundrect
			(at 0.48 0)
			(size 0.59 0.64)
			(layers "B.Cu" "B.Mask" "B.Paste")
			(roundrect_rratio 0.25)
			(net 809 "VIN_MGMT_EN")
			(pintype "passive")
		)
	)
)
